# BASEBOARD_FAB2 (Tioga Pass) — schematic netlist excerpt (pin names and nets, part order shuffled) for the footprints in the layout excerpt that follows; sources: Cadence DE-HDL packaged netlist, KiCad conversion of Wiwynn_Tioga_Pass_MB.brd

T1P5  TPAD-DIFF-4P-GP  pkg DISCRET-GB3  page 256
  \1\  = L12_85OHM_6INCH_DP
  \2\  = L12_85OHM_6INCH_DN
  GND1  = GND
  GND2  = GND

J8C1  CONN3_C95678002  CONN  pkg PIP  page 156
  IO1  = SMB_HOST_STBY_LVC3_SDA
  IO2  = GND
  IO3  = SMB_HOST_STBY_LVC3_SCL

(kicad_pcb
	(version 20260206)
	(generator "pcbnew")
	(generator_version "10.0")
	(general
		(thickness 1.6)
		(legacy_teardrops no)
	)
	(paper "A4")
	(title_block
		(title "Wiwynn_Tioga_Pass_MB.brd")
		(comment 1 "Tioga Pass / footprints 1180-1181 of 4770")
	)
	(layers
		(0 "F.Cu" signal "TOP")
		(4 "In1.Cu" signal "L2GND")
		(6 "In2.Cu" signal "L3")
		(8 "In3.Cu" signal "L4GND")
		(10 "In4.Cu" signal "L5")
		(12 "In5.Cu" signal "L6GND")
		(14 "In6.Cu" signal "L7VCC")
		(16 "In7.Cu" signal "L8VCC")
		(18 "In8.Cu" signal "L9GND")
		(20 "In9.Cu" signal "L10")
		(22 "In10.Cu" signal "L11GND")
		(24 "In11.Cu" signal "L12")
		(26 "In12.Cu" signal "L13GND")
		(2 "B.Cu" signal "BOTTOM")
		(9 "F.Adhes" user "F.Adhesive")
		(11 "B.Adhes" user "B.Adhesive")
		(13 "F.Paste" user "Package Geometry/Pastemask Top")
		(15 "B.Paste" user "Package Geometry/Pastemask Bottom")
		(5 "F.SilkS" user "Ref Des/Silkscreen Top")
		(7 "B.SilkS" user "Ref Des/Silkscreen Bottom")
		(1 "F.Mask" user "Board Geometry/Soldermask Top")
		(3 "B.Mask" user "Board Geometry/Soldermask Bottom")
		(17 "Dwgs.User" user "User.Drawings")
		(19 "Cmts.User" user "User.Comments")
		(21 "Eco1.User" user "User.Eco1")
		(23 "Eco2.User" user "User.Eco2")
		(25 "Edge.Cuts" user "Board Geometry/Outline")
		(27 "Margin" user)
		(31 "F.CrtYd" user "Package Geometry/Place Bound Top")
		(29 "B.CrtYd" user "Package Geometry/Place Bound Bottom")
		(35 "F.Fab" user "Ref Des/Assembly Top")
		(33 "B.Fab" user "Ref Des/Assembly Bottom")
	)
	(footprint ""
		(layer "F.Cu")
		(at 480.335844 -150.39467 180)
		(property "Reference" "J8C1"
			(at 5.66801 2.02184 90)
			(unlocked yes)
			(layer "F.SilkS")
			(effects
				(font
					(size 0.7874 0.5842)
					(thickness 0.1524)
				)
			)
		)
		(property "Value" ""
			(at 0 0 180)
			(layer "F.Fab")
			(effects
				(font
					(size 1.27 1.27)
				)
			)
		)
		(duplicate_pad_numbers_are_jumpers no)
		(fp_line
			(start 1.27 6.54939)
			(end -1.27 6.54939)
			(stroke
				(width 0.1524)
				(type default)
			)
			(layer "F.SilkS")
		)
		(fp_line
			(start 1.27 -1.46939)
			(end 1.27 6.54939)
			(stroke
				(width 0.1524)
				(type default)
			)
			(layer "F.SilkS")
		)
		(fp_line
			(start -1.27 6.54939)
			(end -1.27 -1.46939)
			(stroke
				(width 0.1524)
				(type default)
			)
			(layer "F.SilkS")
		)
		(fp_line
			(start -1.27 -1.46939)
			(end 1.27 -1.46939)
			(stroke
				(width 0.1524)
				(type default)
			)
			(layer "F.SilkS")
		)
		(fp_poly
			(pts
				(xy 2.662682 0.546862) (xy 2.662682 1.562862) (xy 1.392682 1.054862)
			)
			(stroke
				(width 0)
				(type default)
			)
			(fill yes)
			(layer "F.SilkS")
		)
		(fp_poly
			(pts
				(xy 2.148078 -0.52197) (xy 2.148078 0.49403) (xy 0.878078 -0.01397)
			)
			(stroke
				(width 0)
				(type default)
			)
			(fill yes)
			(layer "B.SilkS")
		)
		(fp_poly
			(pts
				(xy 1.27 6.54939) (xy 1.27 -1.46939) (xy -1.27 -1.46939) (xy -1.27 6.54939)
			)
			(stroke
				(width 0)
				(type default)
			)
			(fill no)
			(layer "F.CrtYd")
		)
		(fp_poly
			(pts
				(xy -3.17246 0.38862) (xy -3.17246 -0.62738) (xy -1.90246 -0.11938)
			)
			(stroke
				(width 0)
				(type default)
			)
			(fill yes)
			(layer "B.Fab")
		)
		(fp_line
			(start 1.27 6.54939)
			(end -1.27 6.54939)
			(stroke
				(width 0.1)
				(type default)
			)
			(layer "F.Fab")
		)
		(fp_line
			(start 1.27 -1.46939)
			(end 1.27 6.54939)
			(stroke
				(width 0.1)
				(type default)
			)
			(layer "F.Fab")
		)
		(fp_line
			(start -1.27 6.54939)
			(end -1.27 -1.46939)
			(stroke
				(width 0.1)
				(type default)
			)
			(layer "F.Fab")
		)
		(fp_line
			(start -1.27 -1.46939)
			(end 1.27 -1.46939)
			(stroke
				(width 0.1)
				(type default)
			)
			(layer "F.Fab")
		)
		(fp_poly
			(pts
				(xy -3.17246 0.38862) (xy -3.17246 -0.62738) (xy -1.90246 -0.11938)
			)
			(stroke
				(width 0)
				(type default)
			)
			(fill yes)
			(layer "F.Fab")
		)
		(fp_text user "3"
			(at 2.036064 6.67004 0)
			(unlocked yes)
			(layer "F.SilkS")
			(effects
				(font
					(size 0.7874 0.5842)
					(thickness 0.1524)
				)
				(justify left)
			)
		)
		(fp_text user "3"
			(at 0.258064 6.604 180)
			(unlocked yes)
			(layer "B.SilkS")
			(effects
				(font
					(size 0.7874 0.5842)
					(thickness 0.1524)
				)
				(justify left mirror)
			)
		)
		(fp_text user "3"
			(at 0.247904 6.604 180)
			(unlocked yes)
			(layer "B.Fab")
			(effects
				(font
					(size 0.7874 0.5842)
					(thickness 0.1524)
				)
				(justify left mirror)
			)
		)
		(fp_text user "3"
			(at 1.964944 2.986024 0)
			(unlocked yes)
			(layer "F.Fab")
			(effects
				(font
					(size 0.7874 0.5842)
					(thickness 0.1524)
				)
				(justify left)
			)
		)
		(pad "1" thru_hole rect
			(at 0 0 180)
			(size 1.524 1.524)
			(drill 1.143)
			(layers "*.Cu" "*.Mask")
			(remove_unused_layers no)
			(net "SMB_HOST_STBY_LVC3_SDA")
			(clearance 0.127)
			(thermal_gap 0.127)
			(padstack
				(mode front_inner_back)
				(layer "Inner"
					(shape circle)
					(size 1.524 1.524)
					(clearance 0.127)
				)
				(layer "B.Cu"
					(shape rect)
					(size 1.524 1.524)
					(clearance 0.127)
				)
			)
		)
		(pad "2" thru_hole circle
			(at 0 2.54 180)
			(size 1.524 1.524)
			(drill 1.143)
			(layers "*.Cu" "*.Mask")
			(remove_unused_layers no)
			(net "GND")
			(clearance 0.127)
			(thermal_gap 0.127)
		)
		(pad "3" thru_hole circle
			(at 0 5.08 180)
			(size 1.524 1.524)
			(drill 1.143)
			(layers "*.Cu" "*.Mask")
			(remove_unused_layers no)
			(net "SMB_HOST_STBY_LVC3_SCL")
			(clearance 0.127)
			(thermal_gap 0.127)
		)
	)
	(footprint ""
		(layer "F.Cu")
		(at 221.991936 11.952478 -90)
		(property "Reference" "T1P5"
			(at 0 0 270)
			(layer "F.SilkS")
			(hide yes)
			(effects
				(font
					(size 1.27 1.27)
				)
			)
		)
		(property "Value" "*"
			(at -3.302 1.12395 270)
			(unlocked yes)
			(layer "F.Fab")
			(hide yes)
			(effects
				(font
					(size 0.889 0.889)
					(thickness 0.1524)
				)
			)
		)
		(property "Device Type" "TPAD-DIFF-4P-GP_DISCRET-GB3-TPA"
			(at -3.302 -0.40005 270)
			(unlocked yes)
			(layer "F.Fab")
			(hide yes)
			(effects
				(font
					(size 0.889 0.889)
					(thickness 0.1524)
				)
			)
		)
		(duplicate_pad_numbers_are_jumpers no)
		(fp_line
			(start -2.286 2.286)
			(end 2.286 2.286)
			(stroke
				(width 0.1524)
				(type default)
			)
			(layer "F.SilkS")
		)
		(fp_line
			(start 2.286 2.286)
			(end 2.286 -2.286)
			(stroke
				(width 0.1524)
				(type default)
			)
			(layer "F.SilkS")
		)
		(fp_line
			(start -2.286 -2.286)
			(end -2.286 2.286)
			(stroke
				(width 0.1524)
				(type default)
			)
			(layer "F.SilkS")
		)
		(fp_line
			(start 2.286 -2.286)
			(end -2.286 -2.286)
			(stroke
				(width 0.1524)
				(type default)
			)
			(layer "F.SilkS")
		)
		(fp_line
			(start -2.413 -2.413)
			(end -2.413 -1.143)
			(stroke
				(width 0.4064)
				(type default)
			)
			(layer "F.SilkS")
		)
		(fp_line
			(start -1.143 -2.413)
			(end -2.413 -2.413)
			(stroke
				(width 0.4064)
				(type default)
			)
			(layer "F.SilkS")
		)
		(fp_rect
			(start -2.54 2.54)
			(end 2.54 -2.54)
			(stroke
				(width 0)
				(type default)
			)
			(fill no)
			(layer "F.CrtYd")
		)
		(fp_rect
			(start -2.54 2.54)
			(end 2.54 -2.54)
			(stroke
				(width 0)
				(type default)
			)
			(fill no)
			(layer "F.Fab")
		)
		(pad "1" thru_hole circle
			(at -1.27 -1.27 270)
			(size 1.524 1.524)
			(drill 0.9144)
			(layers "*.Cu" "*.Mask")
			(remove_unused_layers no)
			(net "L12_85OHM_6INCH_DP")
			(clearance -0.0508)
			(thermal_gap 0.127)
			(padstack
				(mode front_inner_back)
				(layer "Inner"
					(shape circle)
					(size 1.1684 1.1684)
					(clearance 0.127)
				)
				(layer "B.Cu"
					(shape circle)
					(size 1.524 1.524)
					(clearance -0.0508)
				)
			)
		)
		(pad "2" thru_hole circle
			(at 1.27 -1.27 270)
			(size 1.524 1.524)
			(drill 0.9144)
			(layers "*.Cu" "*.Mask")
			(remove_unused_layers no)
			(net "L12_85OHM_6INCH_DN")
			(clearance -0.0508)
			(thermal_gap 0.127)
			(padstack
				(mode front_inner_back)
				(layer "Inner"
					(shape circle)
					(size 1.1684 1.1684)
					(clearance 0.127)
				)
				(layer "B.Cu"
					(shape circle)
					(size 1.524 1.524)
					(clearance -0.0508)
				)
			)
		)
		(pad "GND1" thru_hole rect
			(at -1.27 1.27 270)
			(size 1.524 1.524)
			(drill 0.9144)
			(layers "*.Cu" "*.Mask")
			(remove_unused_layers no)
			(net "GND")
			(clearance -0.0508)
			(thermal_gap 0.127)
			(padstack
				(mode front_inner_back)
				(layer "Inner"
					(shape circle)
					(size 1.1684 1.1684)
					(clearance 0.127)
				)
				(layer "B.Cu"
					(shape rect)
					(size 1.524 1.524)
					(clearance -0.0508)
				)
			)
		)
		(pad "GND2" thru_hole rect
			(at 1.27 1.27 270)
			(size 1.524 1.524)
			(drill 0.9144)
			(layers "*.Cu" "*.Mask")
			(remove_unused_layers no)
			(net "GND")
			(clearance -0.0508)
			(thermal_gap 0.127)
			(padstack
				(mode front_inner_back)
				(layer "Inner"
					(shape circle)
					(size 1.1684 1.1684)
					(clearance 0.127)
				)
				(layer "B.Cu"
					(shape rect)
					(size 1.524 1.524)
					(clearance -0.0508)
				)
			)
		)
	)
)
